# SCM (Grand Teton) — schematic netlist excerpt (pin names and nets, part order shuffled) for the footprints in the layout excerpt that follows; sources: Cadence DE-HDL packaged netlist, KiCad conversion of 12092022_DA0F0TMDCD0_F0T_Management_Board_D_brd_V3_OCP.brd

R633  Q_RES  1K 1% EMPTY  pkg 0402LF  page 22 : A = P3V3_AUX ; B = RST_BMC_HW_OUT
R878  Q_RES  0 5% EMPTY  pkg 0402LF  page 56 : A = PWRGD_P1V2_AUX_R2 ; B = EN_P1V0_AUX_R

(kicad_pcb
	(version 20260206)
	(generator "pcbnew")
	(generator_version "10.0")
	(general
		(thickness 1.6)
		(legacy_teardrops no)
	)
	(paper "A4")
	(title_block
		(title "12092022_DA0F0TMDCD0_F0T_Management_Board_D_brd_V3_OCP.brd")
		(comment 1 "Grand Teton / footprints 41-42 of 1440")
	)
	(layers
		(0 "F.Cu" signal "TOP")
		(4 "In1.Cu" signal "GND")
		(6 "In2.Cu" signal "IN1")
		(8 "In3.Cu" signal "GND1")
		(10 "In4.Cu" signal "IN2")
		(12 "In5.Cu" signal "VCC")
		(14 "In6.Cu" signal "VCC1")
		(16 "In7.Cu" signal "IN3")
		(18 "In8.Cu" signal "GND2")
		(20 "In9.Cu" signal "IN4")
		(22 "In10.Cu" signal "GND3")
		(2 "B.Cu" signal "BOTTOM")
		(9 "F.Adhes" user "F.Adhesive")
		(11 "B.Adhes" user "B.Adhesive")
		(13 "F.Paste" user "Package Geometry/Pastemask Top")
		(15 "B.Paste" user "Package Geometry/Pastemask Bottom")
		(5 "F.SilkS" user "Ref Des/Silkscreen Top")
		(7 "B.SilkS" user "Ref Des/Silkscreen Bottom")
		(1 "F.Mask" user "Board Geometry/Soldermask Top")
		(3 "B.Mask" user "Board Geometry/Soldermask Bottom")
		(17 "Dwgs.User" user "User.Drawings")
		(19 "Cmts.User" user "User.Comments")
		(21 "Eco1.User" user "User.Eco1")
		(23 "Eco2.User" user "User.Eco2")
		(25 "Edge.Cuts" user "Board Geometry/Outline")
		(27 "Margin" user)
		(31 "F.CrtYd" user "Package Geometry/Place Bound Top")
		(29 "B.CrtYd" user "Package Geometry/Place Bound Bottom")
		(35 "F.Fab" user "Ref Des/Assembly Top")
		(33 "B.Fab" user "Ref Des/Assembly Bottom")
	)
	(footprint ""
		(layer "F.Cu")
		(at 29.845 -105.41 180)
		(property "Reference" "R633"
			(at 0 0 180)
			(layer "F.SilkS")
			(hide yes)
			(effects
				(font
					(size 1.27 1.27)
				)
			)
		)
		(property "Value" ""
			(at 0 0 180)
			(layer "F.Fab")
			(effects
				(font
					(size 1.27 1.27)
				)
			)
		)
		(duplicate_pad_numbers_are_jumpers no)
		(fp_line
			(start 0.7874 0.4064)
			(end -0.7874 0.4064)
			(stroke
				(width 0.1524)
				(type default)
			)
			(layer "F.SilkS")
		)
		(fp_line
			(start 0.7874 -0.4064)
			(end 0.7874 0.4064)
			(stroke
				(width 0.1524)
				(type default)
			)
			(layer "F.SilkS")
		)
		(fp_line
			(start -0.7874 0.4064)
			(end -0.7874 -0.4064)
			(stroke
				(width 0.1524)
				(type default)
			)
			(layer "F.SilkS")
		)
		(fp_line
			(start -0.7874 -0.4064)
			(end 0.7874 -0.4064)
			(stroke
				(width 0.1524)
				(type default)
			)
			(layer "F.SilkS")
		)
		(fp_line
			(start 0.67945 0.3048)
			(end 0.120396 0.3048)
			(stroke
				(width 0.1)
				(type default)
			)
			(layer "F.Fab")
		)
		(fp_line
			(start 0.67945 -0.3048)
			(end 0.67945 0.3048)
			(stroke
				(width 0.1)
				(type default)
			)
			(layer "F.Fab")
		)
		(fp_line
			(start 0.12065 -0.2794)
			(end 0.12065 -0.3048)
			(stroke
				(width 0.1)
				(type default)
			)
			(layer "F.Fab")
		)
		(fp_line
			(start 0.12065 -0.3048)
			(end 0.67945 -0.3048)
			(stroke
				(width 0.1)
				(type default)
			)
			(layer "F.Fab")
		)
		(fp_line
			(start 0.120396 0.3048)
			(end 0.120396 0.2794)
			(stroke
				(width 0.1)
				(type default)
			)
			(layer "F.Fab")
		)
		(fp_line
			(start 0.120396 0.2794)
			(end -0.12065 0.2794)
			(stroke
				(width 0.1)
				(type default)
			)
			(layer "F.Fab")
		)
		(fp_line
			(start -0.12065 0.3048)
			(end -0.67945 0.3048)
			(stroke
				(width 0.1)
				(type default)
			)
			(layer "F.Fab")
		)
		(fp_line
			(start -0.12065 0.2794)
			(end -0.12065 0.3048)
			(stroke
				(width 0.1)
				(type default)
			)
			(layer "F.Fab")
		)
		(fp_line
			(start -0.12065 -0.2794)
			(end 0.12065 -0.2794)
			(stroke
				(width 0.1)
				(type default)
			)
			(layer "F.Fab")
		)
		(fp_line
			(start -0.12065 -0.305054)
			(end -0.12065 -0.2794)
			(stroke
				(width 0.1)
				(type default)
			)
			(layer "F.Fab")
		)
		(fp_line
			(start -0.67945 0.3048)
			(end -0.67945 -0.305054)
			(stroke
				(width 0.1)
				(type default)
			)
			(layer "F.Fab")
		)
		(fp_line
			(start -0.67945 -0.305054)
			(end -0.12065 -0.305054)
			(stroke
				(width 0.1)
				(type default)
			)
			(layer "F.Fab")
		)
		(pad "1" smd circle
			(at -0.40005 0 180)
			(size 0 0)
			(layers "F.Cu" "F.Mask" "F.Paste")
			(net "P3V3_AUX")
		)
		(pad "2" smd circle
			(at 0.40005 0 180)
			(size 0 0)
			(layers "F.Cu" "F.Mask" "F.Paste")
			(net "RST_BMC_HW_OUT")
		)
	)
	(footprint ""
		(layer "F.Cu")
		(at 15.26286 -31.66364 90)
		(property "Reference" "R878"
			(at 0 0 90)
			(layer "F.SilkS")
			(hide yes)
			(effects
				(font
					(size 1.27 1.27)
				)
			)
		)
		(property "Value" ""
			(at 0 0 90)
			(layer "F.Fab")
			(effects
				(font
					(size 1.27 1.27)
				)
			)
		)
		(duplicate_pad_numbers_are_jumpers no)
		(fp_line
			(start 0.7874 -0.4064)
			(end 0.7874 0.4064)
			(stroke
				(width 0.1524)
				(type default)
			)
			(layer "F.SilkS")
		)
		(fp_line
			(start -0.7874 -0.4064)
			(end 0.7874 -0.4064)
			(stroke
				(width 0.1524)
				(type default)
			)
			(layer "F.SilkS")
		)
		(fp_line
			(start 0.7874 0.4064)
			(end -0.7874 0.4064)
			(stroke
				(width 0.1524)
				(type default)
			)
			(layer "F.SilkS")
		)
		(fp_line
			(start -0.7874 0.4064)
			(end -0.7874 -0.4064)
			(stroke
				(width 0.1524)
				(type default)
			)
			(layer "F.SilkS")
		)
		(fp_line
			(start -0.12065 -0.305054)
			(end -0.12065 -0.2794)
			(stroke
				(width 0.1)
				(type default)
			)
			(layer "F.Fab")
		)
		(fp_line
			(start -0.67945 -0.305054)
			(end -0.12065 -0.305054)
			(stroke
				(width 0.1)
				(type default)
			)
			(layer "F.Fab")
		)
		(fp_line
			(start 0.67945 -0.3048)
			(end 0.67945 0.3048)
			(stroke
				(width 0.1)
				(type default)
			)
			(layer "F.Fab")
		)
		(fp_line
			(start 0.12065 -0.3048)
			(end 0.67945 -0.3048)
			(stroke
				(width 0.1)
				(type default)
			)
			(layer "F.Fab")
		)
		(fp_line
			(start 0.12065 -0.2794)
			(end 0.12065 -0.3048)
			(stroke
				(width 0.1)
				(type default)
			)
			(layer "F.Fab")
		)
		(fp_line
			(start -0.12065 -0.2794)
			(end 0.12065 -0.2794)
			(stroke
				(width 0.1)
				(type default)
			)
			(layer "F.Fab")
		)
		(fp_line
			(start 0.120396 0.2794)
			(end -0.12065 0.2794)
			(stroke
				(width 0.1)
				(type default)
			)
			(layer "F.Fab")
		)
		(fp_line
			(start -0.12065 0.2794)
			(end -0.12065 0.3048)
			(stroke
				(width 0.1)
				(type default)
			)
			(layer "F.Fab")
		)
		(fp_line
			(start 0.67945 0.3048)
			(end 0.120396 0.3048)
			(stroke
				(width 0.1)
				(type default)
			)
			(layer "F.Fab")
		)
		(fp_line
			(start 0.120396 0.3048)
			(end 0.120396 0.2794)
			(stroke
				(width 0.1)
				(type default)
			)
			(layer "F.Fab")
		)
		(fp_line
			(start -0.12065 0.3048)
			(end -0.67945 0.3048)
			(stroke
				(width 0.1)
				(type default)
			)
			(layer "F.Fab")
		)
		(fp_line
			(start -0.67945 0.3048)
			(end -0.67945 -0.305054)
			(stroke
				(width 0.1)
				(type default)
			)
			(layer "F.Fab")
		)
		(pad "1" smd circle
			(at -0.40005 0 90)
			(size 0 0)
			(layers "F.Cu" "F.Mask" "F.Paste")
			(net "PWRGD_P1V2_AUX_R2")
		)
		(pad "2" smd circle
			(at 0.40005 0 90)
			(size 0 0)
			(layers "F.Cu" "F.Mask" "F.Paste")
			(net "EN_P1V0_AUX_R")
		)
	)
)
